(kicad_pcb
	(version 20241229)
	(generator "pcbnew")
	(generator_version "9.0")
	(general
		(thickness 1.6)
		(legacy_teardrops no)
	)
	(paper "A4")
	(title_block
		(title "OCuLink to PCIe adapter")
		(date "2025-06-18")
		(rev "1.0.0")
		(company "Antmicro Ltd")
		(comment 1 "www.antmicro.com")
		(comment 9 "footprints 33-36 of 159")
	)
	(layers
		(0 "F.Cu" signal)
		(4 "In1.Cu" signal)
		(6 "In2.Cu" signal)
		(2 "B.Cu" signal)
		(9 "F.Adhes" user "F.Adhesive")
		(11 "B.Adhes" user "B.Adhesive")
		(13 "F.Paste" user)
		(15 "B.Paste" user)
		(5 "F.SilkS" user "F.Silkscreen")
		(7 "B.SilkS" user "B.Silkscreen")
		(1 "F.Mask" user)
		(3 "B.Mask" user)
		(17 "Dwgs.User" user "User.Drawings")
		(19 "Cmts.User" user "User.Comments")
		(21 "Eco1.User" user "User.Eco1")
		(23 "Eco2.User" user "User.Eco2")
		(25 "Edge.Cuts" user)
		(27 "Margin" user)
		(31 "F.CrtYd" user "F.Courtyard")
		(29 "B.CrtYd" user "B.Courtyard")
		(35 "F.Fab" user)
		(33 "B.Fab" user)
	)
	(footprint "antmicro-footprints:USON-10_2.5x1mm_P0.5mm"
		(layer "F.Cu")
		(at 142.579 46.914999 -90)
		(descr "USON-10 2.5x1mm_ Pitch 0.5mm")
		(tags "USON-10 2.5x1mm Pitch 0.5mm")
		(property "Reference" "D15"
			(at 1.085001 -0.421 180)
			(layer "F.SilkS")
			(effects
				(font
					(size 0.7 0.7)
					(thickness 0.15)
				)
				(justify right top)
			)
		)
		(property "Value" "ESD204DQAR"
			(at 0.018 2.499 90)
			(layer "F.Fab")
			(effects
				(font
					(size 0.7 0.7)
					(thickness 0.15)
				)
				(justify right top)
			)
		)
		(property "Datasheet" "https://www.ti.com/lit/ds/symlink/esd204.pdf?ts=1706004844383&ref_url=https%253A%252F%252Fwww.ti.com%252Finterface%252Fdiodes%252Fesd-protection-diodes%252Fproducts.html"
			(at 0 0 90)
			(layer "F.Fab")
			(hide yes)
			(effects
				(font
					(size 1.27 1.27)
					(thickness 0.15)
				)
			)
		)
		(property "Description" "TVS diode array, 30 kV, USON-10, 3.6 V, 0.55 pF"
			(at 0 0 90)
			(layer "F.Fab")
			(hide yes)
			(effects
				(font
					(size 1.27 1.27)
					(thickness 0.15)
				)
			)
		)
		(property "MPN" "ESD204DQAR"
			(at 0 0 270)
			(unlocked yes)
			(layer "F.Fab")
			(hide yes)
			(effects
				(font
					(size 1 1)
					(thickness 0.15)
				)
			)
		)
		(property "Manufacturer" "Texas Instruments"
			(at 0 0 270)
			(unlocked yes)
			(layer "F.Fab")
			(hide yes)
			(effects
				(font
					(size 1 1)
					(thickness 0.15)
				)
			)
		)
		(property "Author" "Antmicro"
			(at 0 0 270)
			(unlocked yes)
			(layer "F.Fab")
			(hide yes)
			(effects
				(font
					(size 1 1)
					(thickness 0.15)
				)
			)
		)
		(property "License" "Apache-2.0"
			(at 0 0 270)
			(unlocked yes)
			(layer "F.Fab")
			(hide yes)
			(effects
				(font
					(size 1 1)
					(thickness 0.15)
				)
			)
		)
		(sheetname "/OCuLink/")
		(sheetfile "oculink.kicad_sch")
		(attr smd)
		(fp_line
			(start 0.498 1.398)
			(end -0.5 1.398)
			(stroke
				(width 0.15)
				(type solid)
			)
			(layer "F.SilkS")
		)
		(fp_line
			(start 0.498 -1.401)
			(end -0.5 -1.401)
			(stroke
				(width 0.15)
				(type solid)
			)
			(layer "F.SilkS")
		)
		(fp_circle
			(center -0.68 -1.27)
			(end -0.63 -1.27)
			(stroke
				(width 0.15)
				(type solid)
			)
			(fill yes)
			(layer "F.SilkS")
		)
		(fp_rect
			(start -0.8 -1.5)
			(end 0.8 1.499)
			(stroke
				(width 0.05)
				(type solid)
			)
			(fill no)
			(layer "F.CrtYd")
		)
		(fp_line
			(start -0.5 1.249)
			(end 0.498 1.249)
			(stroke
				(width 0.15)
				(type solid)
			)
			(layer "F.Fab")
		)
		(fp_line
			(start -0.5 -1)
			(end -0.5 1.249)
			(stroke
				(width 0.15)
				(type solid)
			)
			(layer "F.Fab")
		)
		(fp_line
			(start -0.25 -1.25)
			(end -0.5 -1)
			(stroke
				(width 0.15)
				(type solid)
			)
			(layer "F.Fab")
		)
		(fp_line
			(start 0.498 -1.25)
			(end 0.498 1.249)
			(stroke
				(width 0.15)
				(type solid)
			)
			(layer "F.Fab")
		)
		(fp_line
			(start 0.498 -1.25)
			(end -0.25 -1.25)
			(stroke
				(width 0.15)
				(type solid)
			)
			(layer "F.Fab")
		)
		(fp_text user "${REFERENCE}"
			(at 0 -0.000501 90)
			(layer "F.Fab")
			(effects
				(font
					(size 0.7 0.7)
					(thickness 0.15)
				)
				(justify right top)
			)
		)
		(fp_text user "Author: Antmicro"
			(at -0.802 5.7 90)
			(layer "F.Fab")
			(effects
				(font
					(size 0.7 0.7)
					(thickness 0.15)
				)
				(justify right top)
			)
		)
		(fp_text user "License: Apache-2.0"
			(at -0.802 6.9 90)
			(layer "F.Fab")
			(effects
				(font
					(size 0.7 0.7)
					(thickness 0.15)
				)
				(justify right top)
			)
		)
		(pad "1" smd roundrect
			(at -0.387 -1 180)
			(size 0.25 0.55)
			(layers "F.Cu" "F.Mask" "F.Paste")
			(roundrect_rratio 0.25)
			(net 182 "/OCuLink/~{CPRSNTC}")
			(pintype "passive")
		)
		(pad "2" smd roundrect
			(at -0.387 -0.5 180)
			(size 0.25 0.55)
			(layers "F.Cu" "F.Mask" "F.Paste")
			(roundrect_rratio 0.25)
			(net 183 "/OCuLink/~{PERSTC}")
			(pintype "passive")
		)
		(pad "3" smd roundrect
			(at -0.387 0 180)
			(size 0.4 0.55)
			(layers "F.Cu" "F.Mask" "F.Paste")
			(roundrect_rratio 0.25)
			(net 66 "GND")
			(pintype "power_in")
		)
		(pad "4" smd roundrect
			(at -0.387 0.498 180)
			(size 0.25 0.55)
			(layers "F.Cu" "F.Mask" "F.Paste")
			(roundrect_rratio 0.25)
			(net 95 "/OCuLink/I2C0C_SDA")
			(pintype "passive")
		)
		(pad "5" smd roundrect
			(at -0.387 0.998 180)
			(size 0.25 0.55)
			(layers "F.Cu" "F.Mask" "F.Paste")
			(roundrect_rratio 0.25)
			(net 101 "/OCuLink/I2C0C_SCL")
			(pintype "passive")
		)
		(pad "6" smd roundrect
			(at 0.385 0.998 180)
			(size 0.25 0.55)
			(layers "F.Cu" "F.Mask" "F.Paste")
			(roundrect_rratio 0.25)
			(net 101 "/OCuLink/I2C0C_SCL")
			(pintype "passive")
		)
		(pad "7" smd roundrect
			(at 0.385 0.498 180)
			(size 0.25 0.55)
			(layers "F.Cu" "F.Mask" "F.Paste")
			(roundrect_rratio 0.25)
			(net 95 "/OCuLink/I2C0C_SDA")
			(pintype "passive")
		)
		(pad "8" smd roundrect
			(at 0.385 0 180)
			(size 0.4 0.55)
			(layers "F.Cu" "F.Mask" "F.Paste")
			(roundrect_rratio 0.25)
			(net 66 "GND")
			(pintype "passive")
		)
		(pad "9" smd roundrect
			(at 0.385 -0.5 180)
			(size 0.25 0.55)
			(layers "F.Cu" "F.Mask" "F.Paste")
			(roundrect_rratio 0.25)
			(net 183 "/OCuLink/~{PERSTC}")
			(pintype "passive")
		)
		(pad "10" smd roundrect
			(at 0.385 -1 180)
			(size 0.25 0.55)
			(layers "F.Cu" "F.Mask" "F.Paste")
			(roundrect_rratio 0.25)
			(net 182 "/OCuLink/~{CPRSNTC}")
			(pintype "passive")
		)
	)
	(footprint "antmicro-footprints:SOD-123FL"
		(layer "F.Cu")
		(at 120.571 123.6)
		(property "Reference" "D9"
			(at -0.571 -1.4 180)
			(layer "F.SilkS")
			(effects
				(font
					(size 0.7 0.7)
					(thickness 0.15)
				)
				(justify left bottom)
			)
		)
		(property "Value" "SZSMF4L14AT3G"
			(at 0 1.967 0)
			(layer "F.Fab")
			(effects
				(font
					(size 0.7 0.7)
					(thickness 0.15)
				)
				(justify left bottom)
			)
		)
		(property "Datasheet" "https://www.mouser.com/datasheet/2/240/media-3320461.pdf"
			(at 0 0 0)
			(layer "F.Fab")
			(hide yes)
			(effects
				(font
					(size 1.27 1.27)
					(thickness 0.15)
				)
			)
		)
		(property "Description" "ESD, TVS Diode, 14V, UNI, 400W, SOD-123FL"
			(at 0 0 0)
			(layer "F.Fab")
			(hide yes)
			(effects
				(font
					(size 1.27 1.27)
					(thickness 0.15)
				)
			)
		)
		(property "MPN" "SZSMF4L12AT3G"
			(at 0 0 0)
			(unlocked yes)
			(layer "F.Fab")
			(hide yes)
			(effects
				(font
					(size 1 1)
					(thickness 0.15)
				)
			)
		)
		(property "Author" "Antmicro"
			(at 0 0 0)
			(unlocked yes)
			(layer "F.Fab")
			(hide yes)
			(effects
				(font
					(size 1 1)
					(thickness 0.15)
				)
			)
		)
		(property "License" "Apache-2.0"
			(at 0 0 0)
			(unlocked yes)
			(layer "F.Fab")
			(hide yes)
			(effects
				(font
					(size 1 1)
					(thickness 0.15)
				)
			)
		)
		(property "Manufacturer" "Littelfuse"
			(at 0 0 0)
			(unlocked yes)
			(layer "F.Fab")
			(hide yes)
			(effects
				(font
					(size 1 1)
					(thickness 0.15)
				)
			)
		)
		(sheetname "/PCIe-connector/")
		(sheetfile "pcie-connector.kicad_sch")
		(attr smd)
		(fp_line
			(start -2.3 -1.1)
			(end -2.3 1.1)
			(stroke
				(width 0.15)
				(type solid)
			)
			(layer "F.SilkS")
		)
		(fp_line
			(start -2.3 1.1)
			(end 0 1.1)
			(stroke
				(width 0.15)
				(type solid)
			)
			(layer "F.SilkS")
		)
		(fp_line
			(start 0 -1.1)
			(end -2.3 -1.1)
			(stroke
				(width 0.15)
				(type solid)
			)
			(layer "F.SilkS")
		)
		(fp_rect
			(start -2.35 -1.125)
			(end 2.35 1.125)
			(stroke
				(width 0.05)
				(type solid)
			)
			(fill no)
			(layer "F.CrtYd")
		)
		(fp_rect
			(start -1.825 -0.875)
			(end 1.824 0.873)
			(stroke
				(width 0.15)
				(type solid)
			)
			(fill no)
			(layer "F.Fab")
		)
		(fp_rect
			(start -0.775 -0.875)
			(end -0.525 0.875)
			(stroke
				(width 0.15)
				(type solid)
			)
			(fill yes)
			(layer "F.Fab")
		)
		(fp_text user "Author: Antmicro"
			(at -2.406 5.168 0)
			(layer "F.Fab")
			(effects
				(font
					(size 0.7 0.7)
					(thickness 0.15)
				)
				(justify left bottom)
			)
		)
		(fp_text user "License: Apache-2.0"
			(at -2.406 6.368 0)
			(layer "F.Fab")
			(effects
				(font
					(size 0.7 0.7)
					(thickness 0.15)
				)
				(justify left bottom)
			)
		)
		(fp_text user "${REFERENCE}"
			(at -2.406 3.967 0)
			(layer "F.Fab")
			(effects
				(font
					(size 0.7 0.7)
					(thickness 0.15)
				)
				(justify left bottom)
			)
		)
		(pad "1" smd roundrect
			(at -1.43 0)
			(size 1.34 1.8)
			(layers "F.Cu" "F.Mask" "F.Paste")
			(roundrect_rratio 0.14)
			(net 87 "+12V")
			(pinfunction "C")
			(pintype "passive")
		)
		(pad "2" smd roundrect
			(at 1.429 0)
			(size 1.34 1.8)
			(layers "F.Cu" "F.Mask" "F.Paste")
			(roundrect_rratio 0.14)
			(net 66 "GND")
			(pinfunction "A")
			(pintype "passive")
		)
	)
	(footprint "antmicro-footprints:Vishay_PowerPAK_1212-8_Single"
		(layer "F.Cu")
		(at 153.4 44.8)
		(descr "PowerPAK 1212-8 Single")
		(tags "Vishay PowerPAK 1212-8 Single")
		(property "Reference" "Q6"
			(at 2 -0.8 180)
			(layer "F.SilkS")
			(effects
				(font
					(size 0.7 0.7)
					(thickness 0.15)
				)
				(justify left bottom)
			)
		)
		(property "Value" "SQS401EN-T1_BE3"
			(at 0 2.7 0)
			(layer "F.Fab")
			(effects
				(font
					(size 0.7 0.7)
					(thickness 0.15)
				)
				(justify left bottom)
			)
		)
		(property "Datasheet" "https://www.vishay.com/docs/65529/sqs401en.pdf"
			(at 0 0 0)
			(layer "F.Fab")
			(hide yes)
			(effects
				(font
					(size 1.27 1.27)
					(thickness 0.15)
				)
			)
		)
		(property "Description" "MOSFET, P Channel, 40 V, 16A, 0.047 ohm, PowerPAK 1212-8, Surface Mount"
			(at 0 0 0)
			(layer "F.Fab")
			(hide yes)
			(effects
				(font
					(size 1.27 1.27)
					(thickness 0.15)
				)
			)
		)
		(property "MPN" "SQS401EN-T1_BE3"
			(at 0 0 0)
			(unlocked yes)
			(layer "F.Fab")
			(hide yes)
			(effects
				(font
					(size 1 1)
					(thickness 0.15)
				)
			)
		)
		(property "Manufacturer" "Vishay"
			(at 0 0 0)
			(unlocked yes)
			(layer "F.Fab")
			(hide yes)
			(effects
				(font
					(size 1 1)
					(thickness 0.15)
				)
			)
		)
		(property "Author" "Antmicro"
			(at 0 0 0)
			(unlocked yes)
			(layer "F.Fab")
			(hide yes)
			(effects
				(font
					(size 1 1)
					(thickness 0.15)
				)
			)
		)
		(property "License" "Apache-2.0"
			(at 0 0 0)
			(unlocked yes)
			(layer "F.Fab")
			(hide yes)
			(effects
				(font
					(size 1 1)
					(thickness 0.15)
				)
			)
		)
		(sheetname "/USB-PD/")
		(sheetfile "usb-pd.kicad_sch")
		(attr smd)
		(fp_line
			(start -1.651 -1.651)
			(end -1.651 -1.317)
			(stroke
				(width 0.15)
				(type solid)
			)
			(layer "F.SilkS")
		)
		(fp_line
			(start -1.651 -1.651)
			(end 1.648 -1.651)
			(stroke
				(width 0.15)
				(type solid)
			)
			(layer "F.SilkS")
		)
		(fp_line
			(start -1.635 1.3)
			(end -1.635 1.634)
			(stroke
				(width 0.15)
				(type solid)
			)
			(layer "F.SilkS")
		)
		(fp_line
			(start -1.635 1.634)
			(end 1.634 1.634)
			(stroke
				(width 0.15)
				(type solid)
			)
			(layer "F.SilkS")
		)
		(fp_line
			(start 1.634 1.3)
			(end 1.634 1.634)
			(stroke
				(width 0.15)
				(type solid)
			)
			(layer "F.SilkS")
		)
		(fp_line
			(start 1.648 -1.651)
			(end 1.648 -1.317)
			(stroke
				(width 0.15)
				(type solid)
			)
			(layer "F.SilkS")
		)
		(fp_circle
			(center -1.9 -1.4)
			(end -1.85 -1.4)
			(stroke
				(width 0.15)
				(type solid)
			)
			(fill yes)
			(layer "F.SilkS")
		)
		(fp_rect
			(start -2 -1.8)
			(end 2 1.798)
			(stroke
				(width 0.05)
				(type solid)
			)
			(fill no)
			(layer "F.CrtYd")
		)
		(fp_line
			(start -1.6425 -1.4175)
			(end -1.4175 -1.6425)
			(stroke
				(width 0.15)
				(type solid)
			)
			(layer "F.Fab")
		)
		(fp_rect
			(start -1.651 -1.651)
			(end 1.648 1.648)
			(stroke
				(width 0.15)
				(type solid)
			)
			(fill no)
			(layer "F.Fab")
		)
		(fp_text user "Author: Antmicro"
			(at -8 5.9 0)
			(layer "F.Fab")
			(effects
				(font
					(size 0.7 0.7)
					(thickness 0.15)
				)
				(justify left bottom)
			)
		)
		(fp_text user "License: Apache-2.0"
			(at -8 7.1 0)
			(layer "F.Fab")
			(effects
				(font
					(size 0.7 0.7)
					(thickness 0.15)
				)
				(justify left bottom)
			)
		)
		(fp_text user "${REFERENCE}"
			(at 0 -0.001 0)
			(layer "F.Fab")
			(effects
				(font
					(size 0.7 0.7)
					(thickness 0.15)
				)
				(justify left bottom)
			)
		)
		(pad "1" smd rect
			(at -1.436 -0.99)
			(size 0.99 0.405)
			(layers "F.Cu" "F.Mask" "F.Paste")
			(net 113 "VBUS")
			(pinfunction "S")
			(pintype "passive")
		)
		(pad "2" smd rect
			(at -1.436 -0.332)
			(size 0.99 0.405)
			(layers "F.Cu" "F.Mask" "F.Paste")
			(net 113 "VBUS")
			(pinfunction "S")
			(pintype "passive")
		)
		(pad "3" smd rect
			(at -1.436 0.33)
			(size 0.99 0.405)
			(layers "F.Cu" "F.Mask" "F.Paste")
			(net 113 "VBUS")
			(pinfunction "S")
			(pintype "passive")
		)
		(pad "4" smd rect
			(at -1.436 0.988)
			(size 0.99 0.405)
			(layers "F.Cu" "F.Mask" "F.Paste")
			(net 84 "Net-(Q6-G)")
			(pinfunction "G")
			(pintype "input")
		)
		(pad "5" smd custom
			(at 0.557 0)
			(size 1.725 2.235)
			(layers "F.Cu" "F.Mask" "F.Paste")
			(net 115 "/USB-PD/VCC")
			(pinfunction "D")
			(pintype "passive")
			(zone_connect 2)
			(options
				(clearance outline)
				(anchor rect)
			)
			(primitives
				(gr_poly
					(pts
						(xy 0.8625 0.1275) (xy 0.8625 -0.1275) (xy 1.3725 -0.1275) (xy 1.3725 -0.5325) (xy 0.8625 -0.5325)
						(xy 0.8625 -0.7875) (xy 1.3725 -0.7875) (xy 1.3725 -1.195) (xy 0.6125 -1.195) (xy 0.6125 1.195)
						(xy 1.3725 1.195) (xy 1.3725 0.7875) (xy 0.8625 0.7875) (xy 0.8625 0.5325) (xy 1.3725 0.5325)
						(xy 1.3725 0.1275)
					)
					(width 0)
					(fill yes)
				)
			)
		)
	)
	(footprint "antmicro-footprints:C_0402_1005Metric"
		(layer "F.Cu")
		(at 151.900001 47.620001 90)
		(descr "Capacitor SMD 0402")
		(tags "capacitor SMD 0402")
		(property "Reference" "C10"
			(at 1.020001 3.699998 90)
			(layer "F.SilkS")
			(effects
				(font
					(size 0.7 0.7)
					(thickness 0.15)
				)
				(justify right top)
			)
		)
		(property "Value" "C_1u_25V_0402"
			(at -1.022927 2.155213 90)
			(layer "F.Fab")
			(effects
				(font
					(size 0.7 0.7)
					(thickness 0.15)
				)
				(justify left bottom)
			)
		)
		(property "Datasheet" "https://www.murata.com/products/productdetail?partno=GRM155R61E105KE11%23"
			(at 0 0 90)
			(layer "F.Fab")
			(hide yes)
			(effects
				(font
					(size 1.27 1.27)
					(thickness 0.15)
				)
			)
		)
		(property "Description" "SMD Multilayer Ceramic Capacitor, 1 µF, 25 V, 0402 [1005 Metric], ± 10%, X5R, GRM Series"
			(at 0 0 90)
			(layer "F.Fab")
			(hide yes)
			(effects
				(font
					(size 1.27 1.27)
					(thickness 0.15)
				)
			)
		)
		(property "MPN" "GRM155R61E105KE11J"
			(at 0 0 90)
			(unlocked yes)
			(layer "F.Fab")
			(hide yes)
			(effects
				(font
					(size 1 1)
					(thickness 0.15)
				)
			)
		)
		(property "Manufacturer" "Murata"
			(at 0 0 90)
			(unlocked yes)
			(layer "F.Fab")
			(hide yes)
			(effects
				(font
					(size 1 1)
					(thickness 0.15)
				)
			)
		)
		(property "License" "Apache-2.0"
			(at 0 0 90)
			(unlocked yes)
			(layer "F.Fab")
			(hide yes)
			(effects
				(font
					(size 1 1)
					(thickness 0.15)
				)
			)
		)
		(property "Author" "Antmicro"
			(at 0 0 90)
			(unlocked yes)
			(layer "F.Fab")
			(hide yes)
			(effects
				(font
					(size 1 1)
					(thickness 0.15)
				)
			)
		)
		(property "Val" "1u"
			(at 0 0 90)
			(unlocked yes)
			(layer "F.Fab")
			(hide yes)
			(effects
				(font
					(size 1 1)
					(thickness 0.15)
				)
			)
		)
		(property "Voltage" "25V"
			(at 0 0 90)
			(unlocked yes)
			(layer "F.Fab")
			(hide yes)
			(effects
				(font
					(size 1 1)
					(thickness 0.15)
				)
			)
		)
		(property "Dielectric" "X5R"
			(at 0 0 90)
			(unlocked yes)
			(layer "F.Fab")
			(hide yes)
			(effects
				(font
					(size 1 1)
					(thickness 0.15)
				)
			)
		)
		(sheetname "/USB-PD/")
		(sheetfile "usb-pd.kicad_sch")
		(attr smd)
		(fp_rect
			(start -0.925 -0.47)
			(end 0.925 0.47)
			(stroke
				(width 0.05)
				(type default)
			)
			(fill no)
			(layer "F.CrtYd")
		)
		(fp_line
			(start 0.504 -0.25)
			(end 0.504 0.248)
			(stroke
				(width 0.15)
				(type solid)
			)
			(layer "F.Fab")
		)
		(fp_line
			(start -0.494 -0.25)
			(end 0.504 -0.25)
			(stroke
				(width 0.15)
				(type solid)
			)
			(layer "F.Fab")
		)
		(fp_line
			(start 0.504 0.248)
			(end -0.494 0.248)
			(stroke
				(width 0.15)
				(type solid)
			)
			(layer "F.Fab")
		)
		(fp_line
			(start -0.494 0.248)
			(end -0.494 -0.25)
			(stroke
				(width 0.15)
				(type solid)
			)
			(layer "F.Fab")
		)
		(fp_text user "License: Apache-2.0"
			(at -0.939 5.799 90)
			(layer "F.Fab")
			(effects
				(font
					(size 0.7 0.7)
					(thickness 0.15)
				)
				(justify left bottom)
			)
		)
		(fp_text user "Author: Antmicro"
			(at -0.939 3.399 90)
			(layer "F.Fab")
			(effects
				(font
					(size 0.7 0.7)
					(thickness 0.15)
				)
				(justify left bottom)
			)
		)
		(fp_text user "${REFERENCE}"
			(at 0 0 270)
			(layer "F.Fab")
			(effects
				(font
					(size 0.7 0.7)
					(thickness 0.15)
				)
				(justify right top)
			)
		)
		(pad "1" smd roundrect
			(at -0.48 0 90)
			(size 0.59 0.64)
			(layers "F.Cu" "F.Mask" "F.Paste")
			(roundrect_rratio 0.25)
			(net 84 "Net-(Q6-G)")
			(pintype "passive")
		)
		(pad "2" smd roundrect
			(at 0.48 0 90)
			(size 0.59 0.64)
			(layers "F.Cu" "F.Mask" "F.Paste")
			(roundrect_rratio 0.25)
			(net 113 "VBUS")
			(pintype "passive")
		)
	)
)
